(kicad_pcb
	(version 20260206)
	(generator "pcbnew")
	(generator_version "10.0")
	(general
		(thickness 1.6)
		(legacy_teardrops no)
	)
	(paper "A4")
	(title_block
		(title "03242023_DA0F0TMBIJ0_F0T_Motherboard_J_brd_V01_OCP.brd")
		(comment 1 "Grand Teton / footprints 4147-4152 of 6105")
	)
	(layers
		(0 "F.Cu" signal "TOP")
		(4 "In1.Cu" signal "GND")
		(6 "In2.Cu" signal "IN1")
		(8 "In3.Cu" signal "GND1")
		(10 "In4.Cu" signal "IN2")
		(12 "In5.Cu" signal "GND2")
		(14 "In6.Cu" signal "IN3")
		(16 "In7.Cu" signal "GND3")
		(18 "In8.Cu" signal "VCC")
		(20 "In9.Cu" signal "VCC1")
		(22 "In10.Cu" signal "GND4")
		(24 "In11.Cu" signal "IN4")
		(26 "In12.Cu" signal "GND5")
		(28 "In13.Cu" signal "IN5")
		(30 "In14.Cu" signal "GND6")
		(32 "In15.Cu" signal "IN6")
		(34 "In16.Cu" signal "GND7")
		(2 "B.Cu" signal "BOTTOM")
		(9 "F.Adhes" user "F.Adhesive")
		(11 "B.Adhes" user "B.Adhesive")
		(13 "F.Paste" user "Package Geometry/Pastemask Top")
		(15 "B.Paste" user "Package Geometry/Pastemask Bottom")
		(5 "F.SilkS" user "Ref Des/Silkscreen Top")
		(7 "B.SilkS" user "Ref Des/Silkscreen Bottom")
		(1 "F.Mask" user "Board Geometry/Soldermask Top")
		(3 "B.Mask" user "Board Geometry/Soldermask Bottom")
		(17 "Dwgs.User" user "User.Drawings")
		(19 "Cmts.User" user "User.Comments")
		(21 "Eco1.User" user "User.Eco1")
		(23 "Eco2.User" user "User.Eco2")
		(25 "Edge.Cuts" user "Board Geometry/Outline")
		(27 "Margin" user)
		(31 "F.CrtYd" user "Package Geometry/Place Bound Top")
		(29 "B.CrtYd" user "Package Geometry/Place Bound Bottom")
		(35 "F.Fab" user "Ref Des/Assembly Top")
		(33 "B.Fab" user "Ref Des/Assembly Bottom")
	)
	(footprint ""
		(layer "F.Cu")
		(at 113.28908 -397.874998 -90)
		(property "Reference" "R3514"
			(at 0 0 270)
			(layer "F.SilkS")
			(hide yes)
			(effects
				(font
					(size 1.27 1.27)
				)
			)
		)
		(property "Value" ""
			(at 0 0 270)
			(layer "F.Fab")
			(effects
				(font
					(size 1.27 1.27)
				)
			)
		)
		(duplicate_pad_numbers_are_jumpers no)
		(fp_line
			(start -0.7874 0.4064)
			(end -0.7874 -0.4064)
			(stroke
				(width 0.1524)
				(type default)
			)
			(layer "F.SilkS")
		)
		(fp_line
			(start 0.7874 0.4064)
			(end -0.7874 0.4064)
			(stroke
				(width 0.1524)
				(type default)
			)
			(layer "F.SilkS")
		)
		(fp_line
			(start -0.7874 -0.4064)
			(end 0.7874 -0.4064)
			(stroke
				(width 0.1524)
				(type default)
			)
			(layer "F.SilkS")
		)
		(fp_line
			(start 0.7874 -0.4064)
			(end 0.7874 0.4064)
			(stroke
				(width 0.1524)
				(type default)
			)
			(layer "F.SilkS")
		)
		(fp_line
			(start -0.67945 0.3048)
			(end -0.67945 -0.305054)
			(stroke
				(width 0.1)
				(type default)
			)
			(layer "F.Fab")
		)
		(fp_line
			(start -0.12065 0.3048)
			(end -0.67945 0.3048)
			(stroke
				(width 0.1)
				(type default)
			)
			(layer "F.Fab")
		)
		(fp_line
			(start 0.120396 0.3048)
			(end 0.120396 0.2794)
			(stroke
				(width 0.1)
				(type default)
			)
			(layer "F.Fab")
		)
		(fp_line
			(start 0.67945 0.3048)
			(end 0.120396 0.3048)
			(stroke
				(width 0.1)
				(type default)
			)
			(layer "F.Fab")
		)
		(fp_line
			(start -0.12065 0.2794)
			(end -0.12065 0.3048)
			(stroke
				(width 0.1)
				(type default)
			)
			(layer "F.Fab")
		)
		(fp_line
			(start 0.120396 0.2794)
			(end -0.12065 0.2794)
			(stroke
				(width 0.1)
				(type default)
			)
			(layer "F.Fab")
		)
		(fp_line
			(start -0.12065 -0.2794)
			(end 0.12065 -0.2794)
			(stroke
				(width 0.1)
				(type default)
			)
			(layer "F.Fab")
		)
		(fp_line
			(start 0.12065 -0.2794)
			(end 0.12065 -0.3048)
			(stroke
				(width 0.1)
				(type default)
			)
			(layer "F.Fab")
		)
		(fp_line
			(start 0.12065 -0.3048)
			(end 0.67945 -0.3048)
			(stroke
				(width 0.1)
				(type default)
			)
			(layer "F.Fab")
		)
		(fp_line
			(start 0.67945 -0.3048)
			(end 0.67945 0.3048)
			(stroke
				(width 0.1)
				(type default)
			)
			(layer "F.Fab")
		)
		(fp_line
			(start -0.67945 -0.305054)
			(end -0.12065 -0.305054)
			(stroke
				(width 0.1)
				(type default)
			)
			(layer "F.Fab")
		)
		(fp_line
			(start -0.12065 -0.305054)
			(end -0.12065 -0.2794)
			(stroke
				(width 0.1)
				(type default)
			)
			(layer "F.Fab")
		)
		(pad "1" smd circle
			(at -0.40005 0 270)
			(size 0 0)
			(layers "F.Cu" "F.Mask" "F.Paste")
			(net "P3V3_AUX")
		)
		(pad "2" smd circle
			(at 0.40005 0 270)
			(size 0 0)
			(layers "F.Cu" "F.Mask" "F.Paste")
			(net "FM_SMB_2_ALERT_GPU_N")
		)
	)
	(footprint ""
		(layer "F.Cu")
		(at 176.317148 -358.12476)
		(property "Reference" "PC724_P1_1"
			(at 0 0 0)
			(layer "F.SilkS")
			(hide yes)
			(effects
				(font
					(size 1.27 1.27)
				)
			)
		)
		(property "Value" ""
			(at 0 0 0)
			(layer "F.Fab")
			(effects
				(font
					(size 1.27 1.27)
				)
			)
		)
		(duplicate_pad_numbers_are_jumpers no)
		(fp_line
			(start -1.524 -0.762)
			(end 1.524 -0.762)
			(stroke
				(width 0.1524)
				(type default)
			)
			(layer "F.SilkS")
		)
		(fp_line
			(start -1.524 0.762)
			(end -1.524 -0.762)
			(stroke
				(width 0.1524)
				(type default)
			)
			(layer "F.SilkS")
		)
		(fp_line
			(start 1.524 -0.762)
			(end 1.524 0.762)
			(stroke
				(width 0.1524)
				(type default)
			)
			(layer "F.SilkS")
		)
		(fp_line
			(start 1.524 0.762)
			(end -1.524 0.762)
			(stroke
				(width 0.1524)
				(type default)
			)
			(layer "F.SilkS")
		)
		(fp_line
			(start -1.1049 -0.724916)
			(end -1.1049 0.724916)
			(stroke
				(width 0.1)
				(type default)
			)
			(layer "F.Fab")
		)
		(fp_line
			(start -1.1049 0.724916)
			(end 1.1049 0.724916)
			(stroke
				(width 0.1)
				(type default)
			)
			(layer "F.Fab")
		)
		(fp_line
			(start 1.1049 -0.724916)
			(end -1.1049 -0.724916)
			(stroke
				(width 0.1)
				(type default)
			)
			(layer "F.Fab")
		)
		(fp_line
			(start 1.1049 0.724916)
			(end 1.1049 -0.724916)
			(stroke
				(width 0.1)
				(type default)
			)
			(layer "F.Fab")
		)
		(pad "1" smd rect
			(at -0.889 0 180)
			(size 1.016 1.27)
			(layers "F.Cu" "F.Mask" "F.Paste")
			(net "SW_P12V_PVCCFA_EHV_FIVRA_CPU1_R")
		)
		(pad "2" smd rect
			(at 0.889 0 180)
			(size 1.016 1.27)
			(layers "F.Cu" "F.Mask" "F.Paste")
			(net "GND")
		)
	)
	(footprint ""
		(layer "F.Cu")
		(at 142.0622 -106.364278 90)
		(property "Reference" "R4041"
			(at 0 0 90)
			(layer "F.SilkS")
			(hide yes)
			(effects
				(font
					(size 1.27 1.27)
				)
			)
		)
		(property "Value" ""
			(at 0 0 90)
			(layer "F.Fab")
			(effects
				(font
					(size 1.27 1.27)
				)
			)
		)
		(duplicate_pad_numbers_are_jumpers no)
		(fp_line
			(start 0.7874 -0.4064)
			(end 0.7874 0.4064)
			(stroke
				(width 0.1524)
				(type default)
			)
			(layer "F.SilkS")
		)
		(fp_line
			(start -0.7874 -0.4064)
			(end 0.7874 -0.4064)
			(stroke
				(width 0.1524)
				(type default)
			)
			(layer "F.SilkS")
		)
		(fp_line
			(start 0.7874 0.4064)
			(end -0.7874 0.4064)
			(stroke
				(width 0.1524)
				(type default)
			)
			(layer "F.SilkS")
		)
		(fp_line
			(start -0.7874 0.4064)
			(end -0.7874 -0.4064)
			(stroke
				(width 0.1524)
				(type default)
			)
			(layer "F.SilkS")
		)
		(fp_line
			(start -0.12065 -0.305054)
			(end -0.12065 -0.2794)
			(stroke
				(width 0.1)
				(type default)
			)
			(layer "F.Fab")
		)
		(fp_line
			(start -0.67945 -0.305054)
			(end -0.12065 -0.305054)
			(stroke
				(width 0.1)
				(type default)
			)
			(layer "F.Fab")
		)
		(fp_line
			(start 0.67945 -0.3048)
			(end 0.67945 0.3048)
			(stroke
				(width 0.1)
				(type default)
			)
			(layer "F.Fab")
		)
		(fp_line
			(start 0.12065 -0.3048)
			(end 0.67945 -0.3048)
			(stroke
				(width 0.1)
				(type default)
			)
			(layer "F.Fab")
		)
		(fp_line
			(start 0.12065 -0.2794)
			(end 0.12065 -0.3048)
			(stroke
				(width 0.1)
				(type default)
			)
			(layer "F.Fab")
		)
		(fp_line
			(start -0.12065 -0.2794)
			(end 0.12065 -0.2794)
			(stroke
				(width 0.1)
				(type default)
			)
			(layer "F.Fab")
		)
		(fp_line
			(start 0.120396 0.2794)
			(end -0.12065 0.2794)
			(stroke
				(width 0.1)
				(type default)
			)
			(layer "F.Fab")
		)
		(fp_line
			(start -0.12065 0.2794)
			(end -0.12065 0.3048)
			(stroke
				(width 0.1)
				(type default)
			)
			(layer "F.Fab")
		)
		(fp_line
			(start 0.67945 0.3048)
			(end 0.120396 0.3048)
			(stroke
				(width 0.1)
				(type default)
			)
			(layer "F.Fab")
		)
		(fp_line
			(start 0.120396 0.3048)
			(end 0.120396 0.2794)
			(stroke
				(width 0.1)
				(type default)
			)
			(layer "F.Fab")
		)
		(fp_line
			(start -0.12065 0.3048)
			(end -0.67945 0.3048)
			(stroke
				(width 0.1)
				(type default)
			)
			(layer "F.Fab")
		)
		(fp_line
			(start -0.67945 0.3048)
			(end -0.67945 -0.305054)
			(stroke
				(width 0.1)
				(type default)
			)
			(layer "F.Fab")
		)
		(pad "1" smd circle
			(at -0.40005 0 90)
			(size 0 0)
			(layers "F.Cu" "F.Mask" "F.Paste")
			(net "P0V62_CPU0_ERRS_U306_VREF")
		)
		(pad "2" smd circle
			(at 0.40005 0 90)
			(size 0 0)
			(layers "F.Cu" "F.Mask" "F.Paste")
			(net "GND")
		)
	)
	(footprint ""
		(layer "F.Cu")
		(at 184.183782 -40.840152 180)
		(property "Reference" "R3997"
			(at 0 0 180)
			(layer "F.SilkS")
			(hide yes)
			(effects
				(font
					(size 1.27 1.27)
				)
			)
		)
		(property "Value" ""
			(at 0 0 180)
			(layer "F.Fab")
			(effects
				(font
					(size 1.27 1.27)
				)
			)
		)
		(duplicate_pad_numbers_are_jumpers no)
		(fp_line
			(start 0.7874 0.4064)
			(end -0.7874 0.4064)
			(stroke
				(width 0.1524)
				(type default)
			)
			(layer "F.SilkS")
		)
		(fp_line
			(start 0.7874 -0.4064)
			(end 0.7874 0.4064)
			(stroke
				(width 0.1524)
				(type default)
			)
			(layer "F.SilkS")
		)
		(fp_line
			(start -0.7874 0.4064)
			(end -0.7874 -0.4064)
			(stroke
				(width 0.1524)
				(type default)
			)
			(layer "F.SilkS")
		)
		(fp_line
			(start -0.7874 -0.4064)
			(end 0.7874 -0.4064)
			(stroke
				(width 0.1524)
				(type default)
			)
			(layer "F.SilkS")
		)
		(fp_line
			(start 0.67945 0.3048)
			(end 0.120396 0.3048)
			(stroke
				(width 0.1)
				(type default)
			)
			(layer "F.Fab")
		)
		(fp_line
			(start 0.67945 -0.3048)
			(end 0.67945 0.3048)
			(stroke
				(width 0.1)
				(type default)
			)
			(layer "F.Fab")
		)
		(fp_line
			(start 0.12065 -0.2794)
			(end 0.12065 -0.3048)
			(stroke
				(width 0.1)
				(type default)
			)
			(layer "F.Fab")
		)
		(fp_line
			(start 0.12065 -0.3048)
			(end 0.67945 -0.3048)
			(stroke
				(width 0.1)
				(type default)
			)
			(layer "F.Fab")
		)
		(fp_line
			(start 0.120396 0.3048)
			(end 0.120396 0.2794)
			(stroke
				(width 0.1)
				(type default)
			)
			(layer "F.Fab")
		)
		(fp_line
			(start 0.120396 0.2794)
			(end -0.12065 0.2794)
			(stroke
				(width 0.1)
				(type default)
			)
			(layer "F.Fab")
		)
		(fp_line
			(start -0.12065 0.3048)
			(end -0.67945 0.3048)
			(stroke
				(width 0.1)
				(type default)
			)
			(layer "F.Fab")
		)
		(fp_line
			(start -0.12065 0.2794)
			(end -0.12065 0.3048)
			(stroke
				(width 0.1)
				(type default)
			)
			(layer "F.Fab")
		)
		(fp_line
			(start -0.12065 -0.2794)
			(end 0.12065 -0.2794)
			(stroke
				(width 0.1)
				(type default)
			)
			(layer "F.Fab")
		)
		(fp_line
			(start -0.12065 -0.305054)
			(end -0.12065 -0.2794)
			(stroke
				(width 0.1)
				(type default)
			)
			(layer "F.Fab")
		)
		(fp_line
			(start -0.67945 0.3048)
			(end -0.67945 -0.305054)
			(stroke
				(width 0.1)
				(type default)
			)
			(layer "F.Fab")
		)
		(fp_line
			(start -0.67945 -0.305054)
			(end -0.12065 -0.305054)
			(stroke
				(width 0.1)
				(type default)
			)
			(layer "F.Fab")
		)
		(pad "1" smd circle
			(at -0.40005 0 180)
			(size 0 0)
			(layers "F.Cu" "F.Mask" "F.Paste")
			(net "P12V_SCM_UV_R")
		)
		(pad "2" smd circle
			(at 0.40005 0 180)
			(size 0 0)
			(layers "F.Cu" "F.Mask" "F.Paste")
			(net "P12V_SCM_UV")
		)
	)
	(footprint ""
		(layer "F.Cu")
		(at 196.07784 -92.832428 90)
		(property "Reference" "R4611"
			(at 0 0 90)
			(layer "F.SilkS")
			(hide yes)
			(effects
				(font
					(size 1.27 1.27)
				)
			)
		)
		(property "Value" ""
			(at 0 0 90)
			(layer "F.Fab")
			(effects
				(font
					(size 1.27 1.27)
				)
			)
		)
		(duplicate_pad_numbers_are_jumpers no)
		(fp_line
			(start 0.7874 -0.4064)
			(end 0.7874 0.4064)
			(stroke
				(width 0.1524)
				(type default)
			)
			(layer "F.SilkS")
		)
		(fp_line
			(start -0.7874 -0.4064)
			(end 0.7874 -0.4064)
			(stroke
				(width 0.1524)
				(type default)
			)
			(layer "F.SilkS")
		)
		(fp_line
			(start 0.7874 0.4064)
			(end -0.7874 0.4064)
			(stroke
				(width 0.1524)
				(type default)
			)
			(layer "F.SilkS")
		)
		(fp_line
			(start -0.7874 0.4064)
			(end -0.7874 -0.4064)
			(stroke
				(width 0.1524)
				(type default)
			)
			(layer "F.SilkS")
		)
		(fp_line
			(start -0.12065 -0.305054)
			(end -0.12065 -0.2794)
			(stroke
				(width 0.1)
				(type default)
			)
			(layer "F.Fab")
		)
		(fp_line
			(start -0.67945 -0.305054)
			(end -0.12065 -0.305054)
			(stroke
				(width 0.1)
				(type default)
			)
			(layer "F.Fab")
		)
		(fp_line
			(start 0.67945 -0.3048)
			(end 0.67945 0.3048)
			(stroke
				(width 0.1)
				(type default)
			)
			(layer "F.Fab")
		)
		(fp_line
			(start 0.12065 -0.3048)
			(end 0.67945 -0.3048)
			(stroke
				(width 0.1)
				(type default)
			)
			(layer "F.Fab")
		)
		(fp_line
			(start 0.12065 -0.2794)
			(end 0.12065 -0.3048)
			(stroke
				(width 0.1)
				(type default)
			)
			(layer "F.Fab")
		)
		(fp_line
			(start -0.12065 -0.2794)
			(end 0.12065 -0.2794)
			(stroke
				(width 0.1)
				(type default)
			)
			(layer "F.Fab")
		)
		(fp_line
			(start 0.120396 0.2794)
			(end -0.12065 0.2794)
			(stroke
				(width 0.1)
				(type default)
			)
			(layer "F.Fab")
		)
		(fp_line
			(start -0.12065 0.2794)
			(end -0.12065 0.3048)
			(stroke
				(width 0.1)
				(type default)
			)
			(layer "F.Fab")
		)
		(fp_line
			(start 0.67945 0.3048)
			(end 0.120396 0.3048)
			(stroke
				(width 0.1)
				(type default)
			)
			(layer "F.Fab")
		)
		(fp_line
			(start 0.120396 0.3048)
			(end 0.120396 0.2794)
			(stroke
				(width 0.1)
				(type default)
			)
			(layer "F.Fab")
		)
		(fp_line
			(start -0.12065 0.3048)
			(end -0.67945 0.3048)
			(stroke
				(width 0.1)
				(type default)
			)
			(layer "F.Fab")
		)
		(fp_line
			(start -0.67945 0.3048)
			(end -0.67945 -0.305054)
			(stroke
				(width 0.1)
				(type default)
			)
			(layer "F.Fab")
		)
		(pad "1" smd circle
			(at -0.40005 0 90)
			(size 0 0)
			(layers "F.Cu" "F.Mask" "F.Paste")
			(net "FM_BMC_CPU_FBRK_OUT_R_N")
		)
		(pad "2" smd circle
			(at 0.40005 0 90)
			(size 0 0)
			(layers "F.Cu" "F.Mask" "F.Paste")
			(net "FM_BMC_CPU_FBRK_OUT_N")
		)
	)
	(footprint ""
		(layer "F.Cu")
		(at 115.75288 -104.079548 90)
		(property "Reference" "C2249"
			(at 0 0 90)
			(layer "F.SilkS")
			(hide yes)
			(effects
				(font
					(size 1.27 1.27)
				)
			)
		)
		(property "Value" ""
			(at 0 0 90)
			(layer "F.Fab")
			(effects
				(font
					(size 1.27 1.27)
				)
			)
		)
		(duplicate_pad_numbers_are_jumpers no)
		(fp_line
			(start 0.7874 -0.4064)
			(end 0.7874 0.4064)
			(stroke
				(width 0.1524)
				(type default)
			)
			(layer "F.SilkS")
		)
		(fp_line
			(start -0.7874 -0.4064)
			(end 0.7874 -0.4064)
			(stroke
				(width 0.1524)
				(type default)
			)
			(layer "F.SilkS")
		)
		(fp_line
			(start 0.7874 0.4064)
			(end -0.7874 0.4064)
			(stroke
				(width 0.1524)
				(type default)
			)
			(layer "F.SilkS")
		)
		(fp_line
			(start -0.7874 0.4064)
			(end -0.7874 -0.4064)
			(stroke
				(width 0.1524)
				(type default)
			)
			(layer "F.SilkS")
		)
		(fp_line
			(start -0.12065 -0.305054)
			(end -0.12065 -0.2794)
			(stroke
				(width 0.1)
				(type default)
			)
			(layer "F.Fab")
		)
		(fp_line
			(start -0.67945 -0.305054)
			(end -0.12065 -0.305054)
			(stroke
				(width 0.1)
				(type default)
			)
			(layer "F.Fab")
		)
		(fp_line
			(start 0.67945 -0.3048)
			(end 0.67945 0.3048)
			(stroke
				(width 0.1)
				(type default)
			)
			(layer "F.Fab")
		)
		(fp_line
			(start 0.12065 -0.3048)
			(end 0.67945 -0.3048)
			(stroke
				(width 0.1)
				(type default)
			)
			(layer "F.Fab")
		)
		(fp_line
			(start 0.12065 -0.2794)
			(end 0.12065 -0.3048)
			(stroke
				(width 0.1)
				(type default)
			)
			(layer "F.Fab")
		)
		(fp_line
			(start -0.12065 -0.2794)
			(end 0.12065 -0.2794)
			(stroke
				(width 0.1)
				(type default)
			)
			(layer "F.Fab")
		)
		(fp_line
			(start 0.120396 0.2794)
			(end -0.12065 0.2794)
			(stroke
				(width 0.1)
				(type default)
			)
			(layer "F.Fab")
		)
		(fp_line
			(start -0.12065 0.2794)
			(end -0.12065 0.3048)
			(stroke
				(width 0.1)
				(type default)
			)
			(layer "F.Fab")
		)
		(fp_line
			(start 0.67945 0.3048)
			(end 0.120396 0.3048)
			(stroke
				(width 0.1)
				(type default)
			)
			(layer "F.Fab")
		)
		(fp_line
			(start 0.120396 0.3048)
			(end 0.120396 0.2794)
			(stroke
				(width 0.1)
				(type default)
			)
			(layer "F.Fab")
		)
		(fp_line
			(start -0.12065 0.3048)
			(end -0.67945 0.3048)
			(stroke
				(width 0.1)
				(type default)
			)
			(layer "F.Fab")
		)
		(fp_line
			(start -0.67945 0.3048)
			(end -0.67945 -0.305054)
			(stroke
				(width 0.1)
				(type default)
			)
			(layer "F.Fab")
		)
		(pad "1" smd circle
			(at -0.40005 0 90)
			(size 0 0)
			(layers "F.Cu" "F.Mask" "F.Paste")
			(net "P0V62_CPU0_ERRS_VREF")
		)
		(pad "2" smd circle
			(at 0.40005 0 90)
			(size 0 0)
			(layers "F.Cu" "F.Mask" "F.Paste")
			(net "GND")
		)
	)
)
